(kicad_pcb
	(version 20260206)
	(generator "pcbnew")
	(generator_version "10.0")
	(general
		(thickness 1.21888)
		(legacy_teardrops no)
	)
	(paper "A4")
	(title_block
		(title "timecard-v9 — TimeCard-DC-V9_EXP.PcbDoc")
		(comment 1 "Time Appliance Project (Time Card) / footprints 74-81 of 402")
	)
	(layers
		(0 "F.Cu" signal "TOP")
		(4 "In1.Cu" signal "SGND")
		(6 "In2.Cu" signal "IN1")
		(8 "In3.Cu" signal "IN2")
		(10 "In4.Cu" signal "SGND1")
		(2 "B.Cu" signal "BOTTOM")
		(9 "F.Adhes" user "F.Adhesive")
		(11 "B.Adhes" user "B.Adhesive")
		(13 "F.Paste" user "Top Paste")
		(15 "B.Paste" user "Bottom Paste")
		(5 "F.SilkS" user "Top Overlay")
		(7 "B.SilkS" user "Bottom Overlay")
		(1 "F.Mask" user "Top Solder")
		(3 "B.Mask" user "Bottom Solder")
		(17 "Dwgs.User" user "User.Drawings")
		(19 "Cmts.User" user "User.Comments")
		(21 "Eco1.User" user "User.Eco1")
		(23 "Eco2.User" user "User.Eco2")
		(25 "Edge.Cuts" user)
		(27 "Margin" user)
		(31 "F.CrtYd" user "Top Courtyard")
		(29 "B.CrtYd" user "Bottom Courtyard")
		(35 "F.Fab" user "Top Component Center")
		(33 "B.Fab" user "Bottom Component Center")
	)
	(footprint "Vault:RESC1005X40X25LL05T10"
		(layer "F.Cu")
		(at 141.0216 105.0162 180)
		(property "Reference" "R105"
			(at 1.87471 -0.026921 0)
			(unlocked yes)
			(layer "F.SilkS")
			(effects
				(font
					(size 0.762 0.762)
					(thickness 0.2286)
				)
			)
		)
		(property "Value" "DNI_49.9_1%_0402"
			(at -2.579871 11.74372 90)
			(unlocked yes)
			(layer "F.SilkS")
			(hide yes)
			(effects
				(font
					(size 0.762 0.762)
					(thickness 0.2286)
				)
			)
		)
		(sheetname "09-USBUart_PPSMUX_UARTMUX")
		(sheetfile "09-USBUart_PPSMUX_UARTMUX.kicad_sch")
		(duplicate_pad_numbers_are_jumpers no)
		(pad "1" smd rect
			(at -0.375 0 270)
			(size 0.45 0.5)
			(layers "F.Cu" "F.Mask" "F.Paste")
			(net "FPGA_MAC_PPS_OUT-")
		)
		(pad "2" smd rect
			(at 0.375 0 270)
			(size 0.45 0.5)
			(layers "F.Cu" "F.Mask" "F.Paste")
			(net "FPGA_MAC_PPSDIFF_OUT")
		)
	)
	(footprint "Vault:RESC1005X40X25NL05T05"
		(layer "F.Cu")
		(at 115.1216 52.2162 90)
		(property "Reference" "R165"
			(at 0.0032 7.526931 90)
			(unlocked yes)
			(layer "F.SilkS")
			(effects
				(font
					(size 0.762 0.762)
					(thickness 0.2032)
				)
			)
		)
		(property "Value" "DNI_27_1%_0402"
			(at -2.732271 10.270975 0)
			(unlocked yes)
			(layer "F.SilkS")
			(hide yes)
			(effects
				(font
					(size 0.762 0.762)
					(thickness 0.2032)
				)
			)
		)
		(sheetname "11-M2_RCB_MUX")
		(sheetfile "11-M2_RCB_MUX.kicad_sch")
		(duplicate_pad_numbers_are_jumpers no)
		(pad "1" smd rect
			(at -0.45 0 180)
			(size 0.55 0.55)
			(layers "F.Cu" "F.Mask" "F.Paste")
			(net "M2_GPS1_TP2")
		)
		(pad "2" smd rect
			(at 0.45 0 180)
			(size 0.55 0.55)
			(layers "F.Cu" "F.Mask" "F.Paste")
			(net "GPS1_TP2")
		)
	)
	(footprint "Vault:FP-0402-L_1_0_0_05-W_0_5-IPC_A"
		(layer "F.Cu")
		(at 111.0216 80.9162 -90)
		(property "Reference" "C32"
			(at -1.9714 0.126931 270)
			(unlocked yes)
			(layer "F.SilkS")
			(effects
				(font
					(size 0.762 0.762)
					(thickness 0.2286)
				)
			)
		)
		(property "Value" "1uF_16V_0402"
			(at 2.069035 2.567191 270)
			(unlocked yes)
			(layer "F.SilkS")
			(hide yes)
			(effects
				(font
					(size 0.762 0.762)
					(thickness 0.2286)
				)
			)
		)
		(sheetname "05-GPS_IMU_SENSORS")
		(sheetfile "05-GPS_IMU_SENSORS.kicad_sch")
		(duplicate_pad_numbers_are_jumpers no)
		(fp_line
			(start 0.83624 0.73624)
			(end -0.83624 0.73624)
			(stroke
				(width 0.2)
				(type solid)
			)
			(layer "F.SilkS")
		)
		(fp_line
			(start 0.83624 -0.73624)
			(end -0.83624 -0.73624)
			(stroke
				(width 0.2)
				(type solid)
			)
			(layer "F.SilkS")
		)
		(fp_line
			(start -1.03624 0.53624)
			(end -1.03624 -0.53624)
			(stroke
				(width 0.2)
				(type solid)
			)
			(layer "F.CrtYd")
		)
		(fp_line
			(start 1.03623 0.53624)
			(end -1.03624 0.53624)
			(stroke
				(width 0.2)
				(type solid)
			)
			(layer "F.CrtYd")
		)
		(fp_line
			(start 1.03623 0.53624)
			(end 1.03623 -0.53624)
			(stroke
				(width 0.2)
				(type solid)
			)
			(layer "F.CrtYd")
		)
		(fp_line
			(start 1.03623 -0.53624)
			(end -1.03624 -0.53624)
			(stroke
				(width 0.2)
				(type solid)
			)
			(layer "F.CrtYd")
		)
		(fp_line
			(start -1.03624 0.53624)
			(end -1.03624 -0.53624)
			(stroke
				(width 0.2)
				(type solid)
			)
			(layer "F.Fab")
		)
		(fp_line
			(start 1.03623 0.53624)
			(end -1.03624 0.53624)
			(stroke
				(width 0.2)
				(type solid)
			)
			(layer "F.Fab")
		)
		(fp_line
			(start 1.03623 0.53624)
			(end 1.03623 -0.53624)
			(stroke
				(width 0.2)
				(type solid)
			)
			(layer "F.Fab")
		)
		(fp_line
			(start 0 0.5)
			(end 0 -0.5)
			(stroke
				(width 0.1)
				(type solid)
			)
			(layer "F.Fab")
		)
		(fp_line
			(start 0.5 0)
			(end -0.5 0)
			(stroke
				(width 0.1)
				(type solid)
			)
			(layer "F.Fab")
		)
		(fp_line
			(start 1.03623 -0.53624)
			(end -1.03624 -0.53624)
			(stroke
				(width 0.2)
				(type solid)
			)
			(layer "F.Fab")
		)
		(fp_text user "${REFERENCE}"
			(at -0.00001 0.09602 270)
			(unlocked yes)
			(layer "F.Fab")
			(effects
				(font
					(face "Arial")
					(size 0.63 0.63)
					(thickness 0.1)
				)
				(justify left bottom)
			)
		)
		(pad "1" smd rect
			(at -0.47856 0 270)
			(size 0.71535 0.67248)
			(layers "F.Cu" "F.Mask" "F.Paste")
			(net "BNO_P3V3")
			(solder_mask_margin 0)
			(solder_paste_margin 0)
		)
		(pad "2" smd rect
			(at 0.47856 0 270)
			(size 0.71535 0.67248)
			(layers "F.Cu" "F.Mask" "F.Paste")
			(net "GND")
			(solder_mask_margin 0)
			(solder_paste_margin 0)
		)
	)
	(footprint "Vault:RESC1005X40X25NL10T10"
		(layer "F.Cu")
		(at 77.3216 144.0162)
		(property "Reference" "R31"
			(at -0.128605 1.273069 180)
			(unlocked yes)
			(layer "F.SilkS")
			(effects
				(font
					(size 0.762 0.762)
					(thickness 0.2286)
				)
			)
		)
		(property "Value" "4.7K_1%_0402"
			(at 1.612035 2.325871 0)
			(unlocked yes)
			(layer "F.SilkS")
			(hide yes)
			(effects
				(font
					(size 0.762 0.762)
					(thickness 0.2286)
				)
			)
		)
		(sheetname "01-USER_IO")
		(sheetfile "01-USER_IO.kicad_sch")
		(duplicate_pad_numbers_are_jumpers no)
		(pad "1" smd rect
			(at -0.425 0 90)
			(size 0.6 0.65)
			(layers "F.Cu" "F.Mask" "F.Paste")
			(net "+3.3V")
		)
		(pad "2" smd rect
			(at 0.425 0 90)
			(size 0.6 0.65)
			(layers "F.Cu" "F.Mask" "F.Paste")
			(net "ANT4_IO_OUT")
		)
	)
	(footprint "Vault:RESC1005X40X25LL05T10"
		(layer "F.Cu")
		(at 195.5216 125.7162 90)
		(property "Reference" "R168"
			(at 2.4032 0.426921 90)
			(unlocked yes)
			(layer "F.SilkS")
			(effects
				(font
					(size 0.762 0.762)
					(thickness 0.2032)
				)
			)
		)
		(property "Value" "DNI_49.9_1%_0402"
			(at -2.579871 11.71832 0)
			(unlocked yes)
			(layer "F.SilkS")
			(hide yes)
			(effects
				(font
					(size 0.762 0.762)
					(thickness 0.2032)
				)
			)
		)
		(sheetname "11-M2_RCB_MUX")
		(sheetfile "11-M2_RCB_MUX.kicad_sch")
		(duplicate_pad_numbers_are_jumpers no)
		(pad "1" smd rect
			(at -0.375 0 180)
			(size 0.45 0.5)
			(layers "F.Cu" "F.Mask" "F.Paste")
			(net "GPS2_PIN12")
		)
		(pad "2" smd rect
			(at 0.375 0 180)
			(size 0.45 0.5)
			(layers "F.Cu" "F.Mask" "F.Paste")
			(net "RCB_GPS2_PIN12")
		)
	)
	(footprint "SA53:SA53"
		(locked yes)
		(layer "F.Cu")
		(at 108.08908 118.3662 180)
		(property "Reference" "U10"
			(at -22.46112 27.623079 0)
			(unlocked yes)
			(layer "F.SilkS")
			(effects
				(font
					(size 0.762 0.762)
					(thickness 0.2286)
				)
			)
		)
		(property "Value" "MAC-SA5X"
			(at -18.327995 28.437071 180)
			(unlocked yes)
			(layer "F.SilkS")
			(hide yes)
			(effects
				(font
					(size 0.762 0.762)
					(thickness 0.2286)
				)
			)
		)
		(sheetname "06-MAC")
		(sheetfile "06-MAC.kicad_sch")
		(duplicate_pad_numbers_are_jumpers no)
		(fp_line
			(start 26.26748 26.75)
			(end -24.53252 26.75)
			(stroke
				(width 0.254)
				(type solid)
			)
			(layer "F.SilkS")
		)
		(fp_line
			(start 26.26748 -24.05)
			(end 26.26748 26.75)
			(stroke
				(width 0.254)
				(type solid)
			)
			(layer "F.SilkS")
		)
		(fp_line
			(start 26.26748 -24.05)
			(end -24.53252 -24.05)
			(stroke
				(width 0.254)
				(type solid)
			)
			(layer "F.SilkS")
		)
		(fp_line
			(start -24.53252 -24.05)
			(end -24.53252 26.75)
			(stroke
				(width 0.254)
				(type solid)
			)
			(layer "F.SilkS")
		)
		(fp_circle
			(center -15.74749 3.64129)
			(end -15.74749 3.76829)
			(stroke
				(width 0.254)
				(type solid)
			)
			(fill no)
			(layer "F.SilkS")
		)
		(pad "" np_thru_hole circle
			(at -15.05499 -16.94261 180)
			(size 6.096 6.096)
			(drill 2.54)
			(layers "*.Cu" "*.Mask")
			(thermal_bridge_angle 90)
			(padstack
				(mode front_inner_back)
				(layer "Inner"
					(shape circle)
					(size 3.048 3.048)
				)
				(layer "B.Cu"
					(shape circle)
					(size 6.096 6.096)
				)
			)
		)
		(pad "" np_thru_hole circle
			(at -14.98753 19.5926 180)
			(size 6.096 6.096)
			(drill 2.54)
			(layers "*.Cu" "*.Mask")
			(thermal_bridge_angle 90)
			(padstack
				(mode front_inner_back)
				(layer "Inner"
					(shape circle)
					(size 3.048 3.048)
				)
				(layer "B.Cu"
					(shape circle)
					(size 6.096 6.096)
				)
			)
		)
		(pad "" np_thru_hole circle
			(at 16.08749 22.666 180)
			(size 6.096 6.096)
			(drill 2.54)
			(layers "*.Cu" "*.Mask")
			(thermal_bridge_angle 90)
			(padstack
				(mode front_inner_back)
				(layer "Inner"
					(shape circle)
					(size 3.048 3.048)
				)
				(layer "B.Cu"
					(shape circle)
					(size 6.096 6.096)
				)
			)
		)
		(pad "" np_thru_hole circle
			(at 16.72249 -18.442 180)
			(size 6.096 6.096)
			(drill 2.54)
			(layers "*.Cu" "*.Mask")
			(thermal_bridge_angle 90)
			(padstack
				(mode front_inner_back)
				(layer "Inner"
					(shape circle)
					(size 3.048 3.048)
				)
				(layer "B.Cu"
					(shape circle)
					(size 6.096 6.096)
				)
			)
		)
		(pad "1" smd rect
			(at -17.16749 3.64129 270)
			(size 0.25 1.8)
			(layers "F.Cu" "F.Mask" "F.Paste")
			(net "MAC_PPS_IN1+")
		)
		(pad "2" smd rect
			(at -21.16749 3.64129 270)
			(size 0.25 1.8)
			(layers "F.Cu" "F.Mask" "F.Paste")
			(net "MAC_USB+")
		)
		(pad "3" smd rect
			(at -17.16749 3.13329 270)
			(size 0.25 1.8)
			(layers "F.Cu" "F.Mask" "F.Paste")
			(net "MAC_PPS_IN1-")
		)
		(pad "4" smd rect
			(at -21.16749 3.13329 270)
			(size 0.25 1.8)
			(layers "F.Cu" "F.Mask" "F.Paste")
			(net "MAC_USB-")
		)
		(pad "5" smd rect
			(at -17.16749 2.62529 270)
			(size 0.25 1.8)
			(layers "F.Cu" "F.Mask" "F.Paste")
			(net "MAC_PPS_IN0+")
		)
		(pad "6" smd rect
			(at -21.16749 2.62529 270)
			(size 0.25 1.8)
			(layers "F.Cu" "F.Mask" "F.Paste")
			(net "MAC_USB_PWR")
		)
		(pad "7" smd rect
			(at -17.16749 2.11729 270)
			(size 0.25 1.8)
			(layers "F.Cu" "F.Mask" "F.Paste")
			(net "MAC_PPS_IN0-")
		)
		(pad "8" smd rect
			(at -21.16749 2.11729 270)
			(size 0.25 1.8)
			(layers "F.Cu" "F.Mask" "F.Paste")
			(net "GND")
		)
		(pad "9" smd rect
			(at -17.16749 1.60929 270)
			(size 0.25 1.8)
			(layers "F.Cu" "F.Mask" "F.Paste")
			(net "GND")
		)
		(pad "10" smd rect
			(at -21.16749 1.60929 270)
			(size 0.25 1.8)
			(layers "F.Cu" "F.Mask" "F.Paste")
		)
		(pad "11" smd rect
			(at -17.16749 1.10129 270)
			(size 0.25 1.8)
			(layers "F.Cu" "F.Mask" "F.Paste")
		)
		(pad "12" smd rect
			(at -21.16749 1.10129 270)
			(size 0.25 1.8)
			(layers "F.Cu" "F.Mask" "F.Paste")
		)
		(pad "13" smd rect
			(at -17.16749 0.59329 270)
			(size 0.25 1.8)
			(layers "F.Cu" "F.Mask" "F.Paste")
		)
		(pad "14" smd rect
			(at -21.16749 0.59329 270)
			(size 0.25 1.8)
			(layers "F.Cu" "F.Mask" "F.Paste")
		)
		(pad "15" smd rect
			(at -17.16749 0.08529 270)
			(size 0.25 1.8)
			(layers "F.Cu" "F.Mask" "F.Paste")
			(net "GND")
		)
		(pad "16" smd rect
			(at -21.16749 0.08529 270)
			(size 0.25 1.8)
			(layers "F.Cu" "F.Mask" "F.Paste")
		)
		(pad "17" smd rect
			(at -17.16749 -0.42271 270)
			(size 0.25 1.8)
			(layers "F.Cu" "F.Mask" "F.Paste")
			(net "MAC_PPS_OUT+")
		)
		(pad "18" smd rect
			(at -21.16749 -0.42271 270)
			(size 0.25 1.8)
			(layers "F.Cu" "F.Mask" "F.Paste")
		)
		(pad "19" smd rect
			(at -17.16749 -0.93071 270)
			(size 0.25 1.8)
			(layers "F.Cu" "F.Mask" "F.Paste")
			(net "MAC_PPS_OUT-")
		)
		(pad "20" smd rect
			(at -21.16749 -0.93071 270)
			(size 0.25 1.8)
			(layers "F.Cu" "F.Mask" "F.Paste")
			(net "MAC_ALARM")
		)
		(pad "P1" thru_hole circle
			(at 21.16748 21.65 90)
			(size 2.54 2.54)
			(drill 2.0066)
			(layers "*.Cu" "*.Mask")
			(remove_unused_layers no)
			(net "MAC_FREQ_CTRL")
			(thermal_bridge_angle 90)
		)
		(pad "P2" thru_hole circle
			(at 21.16748 1.35 90)
			(size 2.54 2.54)
			(drill 2.0066)
			(layers "*.Cu" "*.Mask")
			(remove_unused_layers no)
			(net "GND")
			(thermal_bridge_angle 90)
		)
		(pad "P3" thru_hole circle
			(at 21.16748 -18.95 90)
			(size 2.54 2.54)
			(drill 2.0066)
			(layers "*.Cu" "*.Mask")
			(remove_unused_layers no)
			(net "MAC_RF_OUT")
			(thermal_bridge_angle 90)
		)
		(pad "P4" thru_hole circle
			(at -19.43252 -18.95 90)
			(size 2.54 2.54)
			(drill 2.0066)
			(layers "*.Cu" "*.Mask")
			(remove_unused_layers no)
			(net "GND")
			(thermal_bridge_angle 90)
		)
		(pad "P5" thru_hole circle
			(at -19.43252 21.65 90)
			(size 2.54 2.54)
			(drill 2.0066)
			(layers "*.Cu" "*.Mask")
			(remove_unused_layers no)
			(net "MAC_VCC")
			(thermal_bridge_angle 90)
		)
		(pad "P6" thru_hole circle
			(at -17.33252 -21.65 90)
			(size 2.54 2.54)
			(drill 2.0066)
			(layers "*.Cu" "*.Mask")
			(remove_unused_layers no)
			(net "MAC_BITE")
			(thermal_bridge_angle 90)
		)
		(pad "P7" thru_hole circle
			(at -14.33252 -21.65 90)
			(size 2.54 2.54)
			(drill 2.0066)
			(layers "*.Cu" "*.Mask")
			(remove_unused_layers no)
			(net "MAC_RX")
			(thermal_bridge_angle 90)
		)
		(pad "P8" thru_hole circle
			(at -11.33252 -21.65 90)
			(size 2.54 2.54)
			(drill 2.0066)
			(layers "*.Cu" "*.Mask")
			(remove_unused_layers no)
			(net "MAC_TX")
			(thermal_bridge_angle 90)
		)
		(pad "P9" thru_hole circle
			(at -8.28452 -21.65 90)
			(size 2.54 2.54)
			(drill 2.0066)
			(layers "*.Cu" "*.Mask")
			(remove_unused_layers no)
			(net "MAC_PPS_IN")
			(thermal_bridge_angle 90)
		)
		(pad "P10" thru_hole circle
			(at -5.23652 -21.65 90)
			(size 2.54 2.54)
			(drill 2.0066)
			(layers "*.Cu" "*.Mask")
			(remove_unused_layers no)
			(net "MAC_PPS_OUT")
			(thermal_bridge_angle 90)
		)
		(zone
			(layer "F.Cu")
			(hatch edge 0.5)
			(connect_pads
				(clearance 0)
			)
			(min_thickness 0.25)
			(keepout
				(tracks allowed)
				(vias allowed)
				(pads allowed)
				(copperpour not_allowed)
				(footprints allowed)
			)
			(placement
				(enabled no)
				(sheetname "")
			)
			(fill
				(thermal_gap 0.5)
				(thermal_bridge_width 0.5)
				(island_removal_mode 0)
			)
			(polygon
				(pts
					(xy 123.58908 121.8662) (xy 123.58909 111.8662) (xy 131.08909 111.8662) (xy 131.08908 121.8662)
				)
			)
		)
		(zone
			(layer "F.Cu")
			(hatch edge 0.5)
			(connect_pads
				(clearance 0)
			)
			(min_thickness 0.25)
			(keepout
				(tracks allowed)
				(vias allowed)
				(pads allowed)
				(copperpour not_allowed)
				(footprints allowed)
			)
			(placement
				(enabled no)
				(sheetname "")
			)
			(fill
				(thermal_gap 0.5)
				(thermal_bridge_width 0.5)
				(island_removal_mode 0)
			)
			(polygon
				(pts
					(xy 132.58908 123.3662) (xy 121.08908 123.3662) (xy 121.08908 110.8662) (xy 132.58908 110.8662)
				)
			)
		)
	)
	(footprint "Vault:CAPC1005X55X25ML05T05"
		(layer "F.Cu")
		(at 120.18072 85.4662 -90)
		(property "Reference" "C39"
			(at -2.3532 0.032189 90)
			(unlocked yes)
			(layer "F.SilkS")
			(effects
				(font
					(size 0.762 0.762)
					(thickness 0.2032)
				)
			)
		)
		(property "Value" "22pF_50V_0402"
			(at -2.808431 9.48378 180)
			(unlocked yes)
			(layer "F.SilkS")
			(hide yes)
			(effects
				(font
					(size 0.762 0.762)
					(thickness 0.2032)
				)
			)
		)
		(sheetname "05-GPS_IMU_SENSORS")
		(sheetfile "05-GPS_IMU_SENSORS.kicad_sch")
		(duplicate_pad_numbers_are_jumpers no)
		(pad "1" smd rect
			(at -0.51 0)
			(size 0.72 0.72)
			(layers "F.Cu" "F.Mask" "F.Paste")
			(net "GND")
		)
		(pad "2" smd rect
			(at 0.51 0)
			(size 0.72 0.72)
			(layers "F.Cu" "F.Mask" "F.Paste")
			(net "BNO_XIN32")
		)
	)
	(footprint "Vault:FP-LTST-C191KGKT-MFG"
		(layer "F.Cu")
		(at 79.4216 55.6162)
		(property "Reference" "D11"
			(at -3.7 1.193345 0)
			(unlocked yes)
			(layer "F.SilkS")
			(effects
				(font
					(size 0.762 0.762)
					(thickness 0.2286)
				)
				(justify left bottom)
			)
		)
		(property "Value" "LTST-C191KGKT"
			(at 2.0903 -0.371355 0)
			(unlocked yes)
			(layer "F.SilkS")
			(hide yes)
			(effects
				(font
					(size 0.762 0.762)
					(thickness 0.2286)
				)
				(justify left bottom)
			)
		)
		(sheetname "02-USER_IO_STATUS")
		(sheetfile "02-USER_IO_STATUS.kicad_sch")
		(duplicate_pad_numbers_are_jumpers no)
		(fp_line
			(start -0.85 -0.775)
			(end 0.85 -0.775)
			(stroke
				(width 0.2)
				(type solid)
			)
			(layer "F.SilkS")
		)
		(fp_line
			(start -0.85 0.775)
			(end 0.85 0.775)
			(stroke
				(width 0.2)
				(type solid)
			)
			(layer "F.SilkS")
		)
		(fp_circle
			(center -1.7 0)
			(end -1.7 -0.125)
			(stroke
				(width 0.25)
				(type solid)
			)
			(fill no)
			(layer "F.SilkS")
		)
		(fp_line
			(start -1.25 -0.55)
			(end 1.25 -0.55)
			(stroke
				(width 0.2)
				(type solid)
			)
			(layer "F.CrtYd")
		)
		(fp_line
			(start -1.25 0.55)
			(end -1.25 -0.55)
			(stroke
				(width 0.2)
				(type solid)
			)
			(layer "F.CrtYd")
		)
		(fp_line
			(start -1.25 0.55)
			(end 1.25 0.55)
			(stroke
				(width 0.2)
				(type solid)
			)
			(layer "F.CrtYd")
		)
		(fp_line
			(start 1.25 0.55)
			(end 1.25 -0.55)
			(stroke
				(width 0.2)
				(type solid)
			)
			(layer "F.CrtYd")
		)
		(fp_line
			(start -1.25 -0.55)
			(end 1.25 -0.55)
			(stroke
				(width 0.2)
				(type solid)
			)
			(layer "F.Fab")
		)
		(fp_line
			(start -1.25 0.55)
			(end -1.25 -0.55)
			(stroke
				(width 0.2)
				(type solid)
			)
			(layer "F.Fab")
		)
		(fp_line
			(start -1.25 0.55)
			(end 1.25 0.55)
			(stroke
				(width 0.2)
				(type solid)
			)
			(layer "F.Fab")
		)
		(fp_line
			(start -0.5 0)
			(end 0.5 0)
			(stroke
				(width 0.1)
				(type solid)
			)
			(layer "F.Fab")
		)
		(fp_line
			(start 0 0.5)
			(end 0 -0.5)
			(stroke
				(width 0.1)
				(type solid)
			)
			(layer "F.Fab")
		)
		(fp_line
			(start 1.25 0.55)
			(end 1.25 -0.55)
			(stroke
				(width 0.2)
				(type solid)
			)
			(layer "F.Fab")
		)
		(fp_text user "${REFERENCE}"
			(at 0 0.29534 360)
			(unlocked yes)
			(layer "F.Fab")
			(effects
				(font
					(face "Arial")
					(size 0.63 0.63)
					(thickness 0.1)
				)
				(justify left bottom)
			)
		)
		(pad "1" smd rect
			(at -0.75 0)
			(size 0.8 0.8)
			(layers "F.Cu" "F.Mask" "F.Paste")
			(net "NetD11_1")
			(solder_mask_margin 0)
			(solder_paste_margin 0)
		)
		(pad "2" smd rect
			(at 0.75 0)
			(size 0.8 0.8)
			(layers "F.Cu" "F.Mask" "F.Paste")
			(net "+3.3V")
			(solder_mask_margin 0)
			(solder_paste_margin 0)
		)
	)
)
